# SCM (Grand Teton) — schematic netlist excerpt (pin names and nets, part order shuffled) for the footprints in the layout excerpt that follows; sources: Cadence DE-HDL packaged netlist, KiCad conversion of 12092022_DA0F0TMDCD0_F0T_Management_Board_D_brd_V3_OCP.brd

PC227  Q_CAP  22UF 10V 20% X6S  pkg C0805  page 52 : A = P3V3_AUX ; B = GND
R647  Q_RES  33.2 1% EMPTY  pkg 0402LF  page 21 : A = EMMC_DT2_R ; B = BMC_EMMC_DT2

(kicad_pcb
	(version 20260206)
	(generator "pcbnew")
	(generator_version "10.0")
	(general
		(thickness 1.6)
		(legacy_teardrops no)
	)
	(paper "A4")
	(title_block
		(title "12092022_DA0F0TMDCD0_F0T_Management_Board_D_brd_V3_OCP.brd")
		(comment 1 "Grand Teton / footprints 368-369 of 1440")
	)
	(layers
		(0 "F.Cu" signal "TOP")
		(4 "In1.Cu" signal "GND")
		(6 "In2.Cu" signal "IN1")
		(8 "In3.Cu" signal "GND1")
		(10 "In4.Cu" signal "IN2")
		(12 "In5.Cu" signal "VCC")
		(14 "In6.Cu" signal "VCC1")
		(16 "In7.Cu" signal "IN3")
		(18 "In8.Cu" signal "GND2")
		(20 "In9.Cu" signal "IN4")
		(22 "In10.Cu" signal "GND3")
		(2 "B.Cu" signal "BOTTOM")
		(9 "F.Adhes" user "F.Adhesive")
		(11 "B.Adhes" user "B.Adhesive")
		(13 "F.Paste" user "Package Geometry/Pastemask Top")
		(15 "B.Paste" user "Package Geometry/Pastemask Bottom")
		(5 "F.SilkS" user "Ref Des/Silkscreen Top")
		(7 "B.SilkS" user "Ref Des/Silkscreen Bottom")
		(1 "F.Mask" user "Board Geometry/Soldermask Top")
		(3 "B.Mask" user "Board Geometry/Soldermask Bottom")
		(17 "Dwgs.User" user "User.Drawings")
		(19 "Cmts.User" user "User.Comments")
		(21 "Eco1.User" user "User.Eco1")
		(23 "Eco2.User" user "User.Eco2")
		(25 "Edge.Cuts" user "Board Geometry/Outline")
		(27 "Margin" user)
		(31 "F.CrtYd" user "Package Geometry/Place Bound Top")
		(29 "B.CrtYd" user "Package Geometry/Place Bound Bottom")
		(35 "F.Fab" user "Ref Des/Assembly Top")
		(33 "B.Fab" user "Ref Des/Assembly Bottom")
	)
	(footprint ""
		(layer "F.Cu")
		(at 6.715252 -78.19009 90)
		(property "Reference" "PC227"
			(at 0 0 90)
			(layer "F.SilkS")
			(hide yes)
			(effects
				(font
					(size 1.27 1.27)
				)
			)
		)
		(property "Value" ""
			(at 0 0 90)
			(layer "F.Fab")
			(effects
				(font
					(size 1.27 1.27)
				)
			)
		)
		(duplicate_pad_numbers_are_jumpers no)
		(fp_line
			(start 1.651 -0.8382)
			(end 1.651 0.8382)
			(stroke
				(width 0.1524)
				(type default)
			)
			(layer "F.SilkS")
		)
		(fp_line
			(start -1.651 -0.8382)
			(end 1.651 -0.8382)
			(stroke
				(width 0.1524)
				(type default)
			)
			(layer "F.SilkS")
		)
		(fp_line
			(start 1.651 0.8382)
			(end -1.651 0.8382)
			(stroke
				(width 0.1524)
				(type default)
			)
			(layer "F.SilkS")
		)
		(fp_line
			(start 0 0.8382)
			(end 0 -0.8382)
			(stroke
				(width 0.1524)
				(type default)
			)
			(layer "F.SilkS")
		)
		(fp_line
			(start -1.651 0.8382)
			(end -1.651 -0.8382)
			(stroke
				(width 0.1524)
				(type default)
			)
			(layer "F.SilkS")
		)
		(fp_line
			(start 1.55956 -0.7366)
			(end 1.524 -0.7366)
			(stroke
				(width 0.1)
				(type default)
			)
			(layer "F.Fab")
		)
		(fp_line
			(start 1.524 -0.7366)
			(end -1.524 -0.7366)
			(stroke
				(width 0.1)
				(type default)
			)
			(layer "F.Fab")
		)
		(fp_line
			(start -1.524 -0.7366)
			(end -1.55956 -0.7366)
			(stroke
				(width 0.1)
				(type default)
			)
			(layer "F.Fab")
		)
		(fp_line
			(start -1.55956 -0.7366)
			(end -1.55956 0.7366)
			(stroke
				(width 0.1)
				(type default)
			)
			(layer "F.Fab")
		)
		(fp_line
			(start 1.55956 0.7366)
			(end 1.55956 -0.7366)
			(stroke
				(width 0.1)
				(type default)
			)
			(layer "F.Fab")
		)
		(fp_line
			(start 1.524 0.7366)
			(end 1.55956 0.7366)
			(stroke
				(width 0.1)
				(type default)
			)
			(layer "F.Fab")
		)
		(fp_line
			(start -1.524 0.7366)
			(end 1.524 0.7366)
			(stroke
				(width 0.1)
				(type default)
			)
			(layer "F.Fab")
		)
		(fp_line
			(start -1.55956 0.7366)
			(end -1.524 0.7366)
			(stroke
				(width 0.1)
				(type default)
			)
			(layer "F.Fab")
		)
		(pad "1" smd rect
			(at -0.94996 0 270)
			(size 1.1176 1.3716)
			(layers "F.Cu" "F.Mask" "F.Paste")
			(net "P3V3_AUX")
		)
		(pad "2" smd rect
			(at 0.94996 0 270)
			(size 1.1176 1.3716)
			(layers "F.Cu" "F.Mask" "F.Paste")
			(net "GND")
		)
	)
	(footprint ""
		(layer "F.Cu")
		(at 34.015172 -83.816952 90)
		(property "Reference" "R647"
			(at 0 0 90)
			(layer "F.SilkS")
			(hide yes)
			(effects
				(font
					(size 1.27 1.27)
				)
			)
		)
		(property "Value" ""
			(at 0 0 90)
			(layer "F.Fab")
			(effects
				(font
					(size 1.27 1.27)
				)
			)
		)
		(duplicate_pad_numbers_are_jumpers no)
		(fp_line
			(start 0.7874 -0.4064)
			(end 0.7874 0.4064)
			(stroke
				(width 0.1524)
				(type default)
			)
			(layer "F.SilkS")
		)
		(fp_line
			(start -0.7874 -0.4064)
			(end 0.7874 -0.4064)
			(stroke
				(width 0.1524)
				(type default)
			)
			(layer "F.SilkS")
		)
		(fp_line
			(start 0.7874 0.4064)
			(end -0.7874 0.4064)
			(stroke
				(width 0.1524)
				(type default)
			)
			(layer "F.SilkS")
		)
		(fp_line
			(start -0.7874 0.4064)
			(end -0.7874 -0.4064)
			(stroke
				(width 0.1524)
				(type default)
			)
			(layer "F.SilkS")
		)
		(fp_line
			(start -0.12065 -0.305054)
			(end -0.12065 -0.2794)
			(stroke
				(width 0.1)
				(type default)
			)
			(layer "F.Fab")
		)
		(fp_line
			(start -0.67945 -0.305054)
			(end -0.12065 -0.305054)
			(stroke
				(width 0.1)
				(type default)
			)
			(layer "F.Fab")
		)
		(fp_line
			(start 0.67945 -0.3048)
			(end 0.67945 0.3048)
			(stroke
				(width 0.1)
				(type default)
			)
			(layer "F.Fab")
		)
		(fp_line
			(start 0.12065 -0.3048)
			(end 0.67945 -0.3048)
			(stroke
				(width 0.1)
				(type default)
			)
			(layer "F.Fab")
		)
		(fp_line
			(start 0.12065 -0.2794)
			(end 0.12065 -0.3048)
			(stroke
				(width 0.1)
				(type default)
			)
			(layer "F.Fab")
		)
		(fp_line
			(start -0.12065 -0.2794)
			(end 0.12065 -0.2794)
			(stroke
				(width 0.1)
				(type default)
			)
			(layer "F.Fab")
		)
		(fp_line
			(start 0.120396 0.2794)
			(end -0.12065 0.2794)
			(stroke
				(width 0.1)
				(type default)
			)
			(layer "F.Fab")
		)
		(fp_line
			(start -0.12065 0.2794)
			(end -0.12065 0.3048)
			(stroke
				(width 0.1)
				(type default)
			)
			(layer "F.Fab")
		)
		(fp_line
			(start 0.67945 0.3048)
			(end 0.120396 0.3048)
			(stroke
				(width 0.1)
				(type default)
			)
			(layer "F.Fab")
		)
		(fp_line
			(start 0.120396 0.3048)
			(end 0.120396 0.2794)
			(stroke
				(width 0.1)
				(type default)
			)
			(layer "F.Fab")
		)
		(fp_line
			(start -0.12065 0.3048)
			(end -0.67945 0.3048)
			(stroke
				(width 0.1)
				(type default)
			)
			(layer "F.Fab")
		)
		(fp_line
			(start -0.67945 0.3048)
			(end -0.67945 -0.305054)
			(stroke
				(width 0.1)
				(type default)
			)
			(layer "F.Fab")
		)
		(pad "1" smd circle
			(at -0.40005 0 90)
			(size 0 0)
			(layers "F.Cu" "F.Mask" "F.Paste")
			(net "EMMC_DT2_R")
		)
		(pad "2" smd circle
			(at 0.40005 0 90)
			(size 0 0)
			(layers "F.Cu" "F.Mask" "F.Paste")
			(net "BMC_EMMC_DT2")
		)
	)
)
